# T6G (Grand Teton) — schematic netlist excerpt (pin names and nets, part order shuffled) for the footprints in the layout excerpt that follows; sources: Cadence DE-HDL packaged netlist, KiCad conversion of 04192023_DAF0TMB3IC0_F0TG_MB_C_brd_V02_OCP.brd

PU294  MAX15090BEWIT  MAX15090BEWI+T IC  pkg BGA28_0-5_3-525X2-065  page 146
  ISENSE  = P12V_E1S_SENSE_0
  VCC  = P12V_E1S_VCC_0
  IN_A3  = P12V_AUX
  OUT_A4  = P12V_E1S_0
  IN_A5  = P12V_AUX
  GATE  = P12V_E1S_GATE_0
  CDLY  = GND
  CB  = P12V_E1S_CB_0
  GND_B2  = GND
  IN_B3  = P12V_AUX
  OUT_B4  = P12V_E1S_0
  IN_B5  = P12V_AUX
  OUT_B6  = P12V_E1S_0
  \en#\  = GND
  GND_C1  = GND
  GND_C2  = GND
  IN_C3  = P12V_AUX
  OUT_C4  = P12V_E1S_0
  IN_C5  = P12V_AUX
  OUT_C6  = P12V_E1S_0
  \fault#\  = P12V_E1S_FAULT_0
  REG  = P12V_E1S_REG_0
  UV  = P12V_E1S_UV_0
  OV  = P12V_E1S_OV_0
  OUT_D4  = P12V_E1S_0
  IN_D5  = P12V_AUX
  OUT_D6  = P12V_E1S_0
  PG  = P12V_E1S_PWRGD_0

(kicad_pcb
	(version 20260206)
	(generator "pcbnew")
	(generator_version "10.0")
	(general
		(thickness 1.6)
		(legacy_teardrops no)
	)
	(paper "A4")
	(title_block
		(title "04192023_DAF0TMB3IC0_F0TG_MB_C_brd_V02_OCP.brd")
		(comment 1 "Grand Teton / footprints 3496-3496 of 8354")
	)
	(layers
		(0 "F.Cu" signal "TOP")
		(4 "In1.Cu" signal "GND")
		(6 "In2.Cu" signal "IN1")
		(8 "In3.Cu" signal "GND1")
		(10 "In4.Cu" signal "IN2")
		(12 "In5.Cu" signal "GND2")
		(14 "In6.Cu" signal "IN3")
		(16 "In7.Cu" signal "GND3")
		(18 "In8.Cu" signal "VCC")
		(20 "In9.Cu" signal "VCC1")
		(22 "In10.Cu" signal "GND4")
		(24 "In11.Cu" signal "IN4")
		(26 "In12.Cu" signal "GND5")
		(28 "In13.Cu" signal "IN5")
		(30 "In14.Cu" signal "GND6")
		(32 "In15.Cu" signal "IN6")
		(34 "In16.Cu" signal "GND7")
		(2 "B.Cu" signal "BOTTOM")
		(9 "F.Adhes" user "F.Adhesive")
		(11 "B.Adhes" user "B.Adhesive")
		(13 "F.Paste" user "Package Geometry/Pastemask Top")
		(15 "B.Paste" user "Package Geometry/Pastemask Bottom")
		(5 "F.SilkS" user "Ref Des/Silkscreen Top")
		(7 "B.SilkS" user "Ref Des/Silkscreen Bottom")
		(1 "F.Mask" user "Board Geometry/Soldermask Top")
		(3 "B.Mask" user "Board Geometry/Soldermask Bottom")
		(17 "Dwgs.User" user "User.Drawings")
		(19 "Cmts.User" user "User.Comments")
		(21 "Eco1.User" user "User.Eco1")
		(23 "Eco2.User" user "User.Eco2")
		(25 "Edge.Cuts" user "Board Geometry/Outline")
		(27 "Margin" user)
		(31 "F.CrtYd" user "Package Geometry/Place Bound Top")
		(29 "B.CrtYd" user "Package Geometry/Place Bound Bottom")
		(35 "F.Fab" user "Ref Des/Assembly Top")
		(33 "B.Fab" user "Ref Des/Assembly Bottom")
	)
	(footprint ""
		(layer "F.Cu")
		(at 252.83287 -42.055542 -90)
		(property "Reference" "PU294"
			(at -0.455168 -1.924812 0)
			(unlocked yes)
			(layer "F.SilkS")
			(effects
				(font
					(size 0.7874 0.5842)
					(thickness 0.1524)
				)
				(justify left)
			)
		)
		(property "Value" ""
			(at 0 0 270)
			(layer "F.Fab")
			(effects
				(font
					(size 1.27 1.27)
				)
			)
		)
		(duplicate_pad_numbers_are_jumpers no)
		(fp_line
			(start -1.774952 1.039876)
			(end 1.774952 1.039876)
			(stroke
				(width 0.1524)
				(type default)
			)
			(layer "F.SilkS")
		)
		(fp_line
			(start 1.774952 1.039876)
			(end 1.774952 -1.039876)
			(stroke
				(width 0.1524)
				(type default)
			)
			(layer "F.SilkS")
		)
		(fp_line
			(start -1.774952 -1.039876)
			(end -1.774952 1.039876)
			(stroke
				(width 0.1524)
				(type default)
			)
			(layer "F.SilkS")
		)
		(fp_line
			(start 1.774952 -1.039876)
			(end -1.774952 -1.039876)
			(stroke
				(width 0.1524)
				(type default)
			)
			(layer "F.SilkS")
		)
		(fp_poly
			(pts
				(xy -0.999998 -1.801876) (xy -0.999998 -1.039876) (xy -1.769872 -1.039876) (xy -1.769872 -0.249936)
				(xy -2.531872 -0.249936) (xy -2.531872 -1.801876)
			)
			(stroke
				(width 0)
				(type default)
			)
			(fill yes)
			(layer "F.SilkS")
		)
		(fp_line
			(start -1.769872 1.039876)
			(end 1.769872 1.039876)
			(stroke
				(width 0.1)
				(type default)
			)
			(layer "F.Fab")
		)
		(fp_line
			(start 1.769872 1.039876)
			(end 1.769872 -1.039876)
			(stroke
				(width 0.1)
				(type default)
			)
			(layer "F.Fab")
		)
		(fp_line
			(start -1.769872 -1.039876)
			(end -1.769872 1.039876)
			(stroke
				(width 0.1)
				(type default)
			)
			(layer "F.Fab")
		)
		(fp_line
			(start 1.769872 -1.039876)
			(end -1.769872 -1.039876)
			(stroke
				(width 0.1)
				(type default)
			)
			(layer "F.Fab")
		)
		(fp_poly
			(pts
				(xy -1.769872 -1.039876) (xy -0.999998 -1.039876) (xy -0.999998 -1.801876) (xy -2.531872 -1.801876)
				(xy -2.531872 -0.249936) (xy -1.769872 -0.249936)
			)
			(stroke
				(width 0)
				(type default)
			)
			(fill yes)
			(layer "F.Fab")
		)
		(pad "A1" smd circle
			(at -1.500124 -0.750062 270)
			(size 0.2286 0.2286)
			(layers "F.Cu" "F.Mask" "F.Paste")
			(net "P12V_E1S_SENSE_0")
		)
		(pad "A2" smd circle
			(at -0.999998 -0.750062 270)
			(size 0.2286 0.2286)
			(layers "F.Cu" "F.Mask" "F.Paste")
			(net "P12V_E1S_VCC_0")
		)
		(pad "A3" smd circle
			(at -0.499872 -0.750062 270)
			(size 0.2286 0.2286)
			(layers "F.Cu" "F.Mask" "F.Paste")
			(net "P12V_AUX")
		)
		(pad "A4" smd circle
			(at 0 -0.750062 270)
			(size 0.2286 0.2286)
			(layers "F.Cu" "F.Mask" "F.Paste")
			(net "P12V_E1S_0")
		)
		(pad "A5" smd circle
			(at 0.499872 -0.750062 270)
			(size 0.2286 0.2286)
			(layers "F.Cu" "F.Mask" "F.Paste")
			(net "P12V_AUX")
		)
		(pad "A6" smd circle
			(at 0.999998 -0.750062 270)
			(size 0.2286 0.2286)
			(layers "F.Cu" "F.Mask" "F.Paste")
			(net "P12V_E1S_GATE_0")
		)
		(pad "A7" smd circle
			(at 1.500124 -0.750062 270)
			(size 0.2286 0.2286)
			(layers "F.Cu" "F.Mask" "F.Paste")
			(net "GND")
		)
		(pad "B1" smd circle
			(at -1.500124 -0.249936 270)
			(size 0.2286 0.2286)
			(layers "F.Cu" "F.Mask" "F.Paste")
			(net "P12V_E1S_CB_0")
		)
		(pad "B2" smd circle
			(at -0.999998 -0.249936 270)
			(size 0.2286 0.2286)
			(layers "F.Cu" "F.Mask" "F.Paste")
			(net "GND")
		)
		(pad "B3" smd circle
			(at -0.499872 -0.249936 270)
			(size 0.2286 0.2286)
			(layers "F.Cu" "F.Mask" "F.Paste")
			(net "P12V_AUX")
		)
		(pad "B4" smd circle
			(at 0 -0.249936 270)
			(size 0.2286 0.2286)
			(layers "F.Cu" "F.Mask" "F.Paste")
			(net "P12V_E1S_0")
		)
		(pad "B5" smd circle
			(at 0.499872 -0.249936 270)
			(size 0.2286 0.2286)
			(layers "F.Cu" "F.Mask" "F.Paste")
			(net "P12V_AUX")
		)
		(pad "B6" smd circle
			(at 0.999998 -0.249936 270)
			(size 0.2286 0.2286)
			(layers "F.Cu" "F.Mask" "F.Paste")
			(net "P12V_E1S_0")
		)
		(pad "B7" smd circle
			(at 1.500124 -0.249936 270)
			(size 0.2286 0.2286)
			(layers "F.Cu" "F.Mask" "F.Paste")
			(net "GND")
		)
		(pad "C1" smd circle
			(at -1.500124 0.249936 270)
			(size 0.2286 0.2286)
			(layers "F.Cu" "F.Mask" "F.Paste")
			(net "GND")
		)
		(pad "C2" smd circle
			(at -0.999998 0.249936 270)
			(size 0.2286 0.2286)
			(layers "F.Cu" "F.Mask" "F.Paste")
			(net "GND")
		)
		(pad "C3" smd circle
			(at -0.499872 0.249936 270)
			(size 0.2286 0.2286)
			(layers "F.Cu" "F.Mask" "F.Paste")
			(net "P12V_AUX")
		)
		(pad "C4" smd circle
			(at 0 0.249936 270)
			(size 0.2286 0.2286)
			(layers "F.Cu" "F.Mask" "F.Paste")
			(net "P12V_E1S_0")
		)
		(pad "C5" smd circle
			(at 0.499872 0.249936 270)
			(size 0.2286 0.2286)
			(layers "F.Cu" "F.Mask" "F.Paste")
			(net "P12V_AUX")
		)
		(pad "C6" smd circle
			(at 0.999998 0.249936 270)
			(size 0.2286 0.2286)
			(layers "F.Cu" "F.Mask" "F.Paste")
			(net "P12V_E1S_0")
		)
		(pad "C7" smd circle
			(at 1.500124 0.249936 270)
			(size 0.2286 0.2286)
			(layers "F.Cu" "F.Mask" "F.Paste")
			(net "P12V_E1S_FAULT_0")
		)
		(pad "D1" smd circle
			(at -1.500124 0.750062 270)
			(size 0.2286 0.2286)
			(layers "F.Cu" "F.Mask" "F.Paste")
			(net "P12V_E1S_REG_0")
		)
		(pad "D2" smd circle
			(at -0.999998 0.750062 270)
			(size 0.2286 0.2286)
			(layers "F.Cu" "F.Mask" "F.Paste")
			(net "P12V_E1S_UV_0")
		)
		(pad "D3" smd circle
			(at -0.499872 0.750062 270)
			(size 0.2286 0.2286)
			(layers "F.Cu" "F.Mask" "F.Paste")
			(net "P12V_E1S_OV_0")
		)
		(pad "D4" smd circle
			(at 0 0.750062 270)
			(size 0.2286 0.2286)
			(layers "F.Cu" "F.Mask" "F.Paste")
			(net "P12V_E1S_0")
		)
		(pad "D5" smd circle
			(at 0.499872 0.750062 270)
			(size 0.2286 0.2286)
			(layers "F.Cu" "F.Mask" "F.Paste")
			(net "P12V_AUX")
		)
		(pad "D6" smd circle
			(at 0.999998 0.750062 270)
			(size 0.2286 0.2286)
			(layers "F.Cu" "F.Mask" "F.Paste")
			(net "P12V_E1S_0")
		)
		(pad "D7" smd circle
			(at 1.500124 0.750062 270)
			(size 0.2286 0.2286)
			(layers "F.Cu" "F.Mask" "F.Paste")
			(net "P12V_E1S_PWRGD_0")
		)
	)
)
